(kicad_pcb
	(version 20260206)
	(generator "pcbnew")
	(generator_version "10.0")
	(general
		(thickness 1.6)
		(legacy_teardrops no)
	)
	(paper "A4")
	(title_block
		(title "fcb — 12433-1M.1206WZS1330.brd")
		(comment 1 "Open Vault / Knox (Wiwynn) / footprints 309-313 of 495")
	)
	(layers
		(0 "F.Cu" signal "TOP")
		(4 "In1.Cu" signal "L2GND")
		(6 "In2.Cu" signal "L3VCC")
		(2 "B.Cu" signal "BOTTOM")
		(9 "F.Adhes" user "F.Adhesive")
		(11 "B.Adhes" user "B.Adhesive")
		(13 "F.Paste" user "Package Geometry/Pastemask Top")
		(15 "B.Paste" user "Package Geometry/Pastemask Bottom")
		(5 "F.SilkS" user "Ref Des/Silkscreen Top")
		(7 "B.SilkS" user "Ref Des/Silkscreen Bottom")
		(1 "F.Mask" user "Board Geometry/Soldermask Top")
		(3 "B.Mask" user "Board Geometry/Soldermask Bottom")
		(17 "Dwgs.User" user "User.Drawings")
		(19 "Cmts.User" user "User.Comments")
		(21 "Eco1.User" user "User.Eco1")
		(23 "Eco2.User" user "User.Eco2")
		(25 "Edge.Cuts" user "Board Geometry/Outline")
		(27 "Margin" user)
		(31 "F.CrtYd" user "Package Geometry/Place Bound Top")
		(29 "B.CrtYd" user "Package Geometry/Place Bound Bottom")
		(35 "F.Fab" user "Ref Des/Assembly Top")
		(33 "B.Fab" user "Ref Des/Assembly Bottom")
	)
	(footprint ""
		(layer "F.Cu")
		(at 10.033 -174.752 90)
		(property "Reference" "U10"
			(at 0 0 90)
			(layer "F.SilkS")
			(hide yes)
			(effects
				(font
					(size 1.27 1.27)
				)
			)
		)
		(property "Value" "74LVC1G32GW-1GP"
			(at -2.3368 -8.6868 90)
			(unlocked yes)
			(layer "F.Fab")
			(hide yes)
			(effects
				(font
					(size 1.016 1.016)
					(thickness 0.1524)
				)
			)
		)
		(property "Device Type" "SC70-5H44"
			(at -2.3114 -10.414 90)
			(unlocked yes)
			(layer "F.Fab")
			(hide yes)
			(effects
				(font
					(size 1.016 1.016)
					(thickness 0.1524)
				)
			)
		)
		(duplicate_pad_numbers_are_jumpers no)
		(fp_line
			(start 1.3843 -1.8034)
			(end 1.3843 -1.1176)
			(stroke
				(width 0.3302)
				(type default)
			)
			(layer "F.SilkS")
		)
		(fp_line
			(start 0.6604 -1.8034)
			(end 1.3843 -1.8034)
			(stroke
				(width 0.3302)
				(type default)
			)
			(layer "F.SilkS")
		)
		(fp_line
			(start 1.27 -1.7018)
			(end 1.27 1.7018)
			(stroke
				(width 0.1524)
				(type default)
			)
			(layer "F.SilkS")
		)
		(fp_line
			(start -1.27 -1.7018)
			(end 1.27 -1.7018)
			(stroke
				(width 0.1524)
				(type default)
			)
			(layer "F.SilkS")
		)
		(fp_line
			(start 1.27 1.7018)
			(end -1.27 1.7018)
			(stroke
				(width 0.1524)
				(type default)
			)
			(layer "F.SilkS")
		)
		(fp_line
			(start -1.27 1.7018)
			(end -1.27 -1.7018)
			(stroke
				(width 0.1524)
				(type default)
			)
			(layer "F.SilkS")
		)
		(fp_rect
			(start -1.524 1.9558)
			(end 1.524 -1.9558)
			(stroke
				(width 0)
				(type default)
			)
			(fill no)
			(layer "F.CrtYd")
		)
		(fp_poly
			(pts
				(xy -1.524 -1.9558) (xy 1.524 -1.9558) (xy 1.524 1.9558) (xy -1.524 1.9558)
			)
			(stroke
				(width 0)
				(type default)
			)
			(fill no)
			(layer "F.Fab")
		)
		(pad "1" smd rect
			(at 0.65024 -0.8255 90)
			(size 0.4064 1.2192)
			(layers "F.Cu" "F.Mask" "F.Paste")
			(net "SEB_PEER_1A_HB")
		)
		(pad "2" smd rect
			(at 0 -0.8255 90)
			(size 0.4064 1.2192)
			(layers "F.Cu" "F.Mask" "F.Paste")
			(net "SEB_PEER_1B_HB")
		)
		(pad "3" smd rect
			(at -0.65024 -0.8255 90)
			(size 0.4064 1.2192)
			(layers "F.Cu" "F.Mask" "F.Paste")
			(net "GND")
		)
		(pad "4" smd rect
			(at -0.65024 0.8255 90)
			(size 0.4064 1.2192)
			(layers "F.Cu" "F.Mask" "F.Paste")
			(net "SEB_PEER_1A_1B_HB_OUT")
		)
		(pad "5" smd rect
			(at 0.65024 0.8255 90)
			(size 0.4064 1.2192)
			(layers "F.Cu" "F.Mask" "F.Paste")
			(net "P3V3")
		)
	)
	(footprint ""
		(layer "F.Cu")
		(at 27.500072 -320.000122 90)
		(property "Reference" "Q2"
			(at 0 0 90)
			(layer "F.SilkS")
			(hide yes)
			(effects
				(font
					(size 1.27 1.27)
				)
			)
		)
		(property "Value" "PMBS3904-1-GP"
			(at 0 -9.0932 90)
			(unlocked yes)
			(layer "F.Fab")
			(hide yes)
			(effects
				(font
					(size 1.016 1.016)
					(thickness 0.1524)
				)
			)
		)
		(property "Device Type" "SOT-23-10H44"
			(at 0 -10.6172 90)
			(unlocked yes)
			(layer "F.Fab")
			(hide yes)
			(effects
				(font
					(size 1.016 1.016)
					(thickness 0.1524)
				)
			)
		)
		(duplicate_pad_numbers_are_jumpers no)
		(fp_line
			(start 1.651 -1.778)
			(end -1.651 -1.778)
			(stroke
				(width 0.1524)
				(type default)
			)
			(layer "F.SilkS")
		)
		(fp_line
			(start -1.651 -1.778)
			(end -1.651 1.778)
			(stroke
				(width 0.1524)
				(type default)
			)
			(layer "F.SilkS")
		)
		(fp_line
			(start 1.651 1.778)
			(end 1.651 -1.778)
			(stroke
				(width 0.1524)
				(type default)
			)
			(layer "F.SilkS")
		)
		(fp_line
			(start -1.651 1.778)
			(end 1.651 1.778)
			(stroke
				(width 0.1524)
				(type default)
			)
			(layer "F.SilkS")
		)
		(fp_line
			(start -0.9906 1.86309)
			(end -0.701294 2.15265)
			(stroke
				(width 0.0127)
				(type default)
			)
			(layer "F.SilkS")
		)
		(fp_line
			(start -0.994156 1.8669)
			(end -0.987044 1.8669)
			(stroke
				(width 0.0127)
				(type default)
			)
			(layer "F.SilkS")
		)
		(fp_line
			(start -1.003808 1.876552)
			(end -0.977646 1.876552)
			(stroke
				(width 0.0127)
				(type default)
			)
			(layer "F.SilkS")
		)
		(fp_line
			(start -0.635 1.8796)
			(end -1.7526 1.8796)
			(stroke
				(width 0.3302)
				(type default)
			)
			(layer "F.SilkS")
		)
		(fp_line
			(start -1.7526 1.8796)
			(end -1.7526 0.9906)
			(stroke
				(width 0.3302)
				(type default)
			)
			(layer "F.SilkS")
		)
		(fp_line
			(start -1.013206 1.88595)
			(end -0.967994 1.88595)
			(stroke
				(width 0.0127)
				(type default)
			)
			(layer "F.SilkS")
		)
		(fp_line
			(start -1.022858 1.895602)
			(end -0.958596 1.895602)
			(stroke
				(width 0.0127)
				(type default)
			)
			(layer "F.SilkS")
		)
		(fp_line
			(start -1.032256 1.905)
			(end -0.948944 1.905)
			(stroke
				(width 0.0127)
				(type default)
			)
			(layer "F.SilkS")
		)
		(fp_line
			(start -1.041908 1.914652)
			(end -0.939546 1.914652)
			(stroke
				(width 0.0127)
				(type default)
			)
			(layer "F.SilkS")
		)
		(fp_line
			(start -1.051306 1.92405)
			(end -0.929894 1.92405)
			(stroke
				(width 0.0127)
				(type default)
			)
			(layer "F.SilkS")
		)
		(fp_line
			(start -1.060958 1.933702)
			(end -0.920496 1.933702)
			(stroke
				(width 0.0127)
				(type default)
			)
			(layer "F.SilkS")
		)
		(fp_line
			(start -1.070356 1.9431)
			(end -0.910844 1.9431)
			(stroke
				(width 0.0127)
				(type default)
			)
			(layer "F.SilkS")
		)
		(fp_line
			(start -1.080008 1.952752)
			(end -0.901446 1.952752)
			(stroke
				(width 0.0127)
				(type default)
			)
			(layer "F.SilkS")
		)
		(fp_line
			(start -1.089406 1.96215)
			(end -0.891794 1.96215)
			(stroke
				(width 0.0127)
				(type default)
			)
			(layer "F.SilkS")
		)
		(fp_line
			(start -1.099058 1.971802)
			(end -0.882396 1.971802)
			(stroke
				(width 0.0127)
				(type default)
			)
			(layer "F.SilkS")
		)
		(fp_line
			(start -1.108456 1.9812)
			(end -0.872744 1.9812)
			(stroke
				(width 0.0127)
				(type default)
			)
			(layer "F.SilkS")
		)
		(fp_line
			(start -1.118108 1.990852)
			(end -0.863346 1.990852)
			(stroke
				(width 0.0127)
				(type default)
			)
			(layer "F.SilkS")
		)
		(fp_line
			(start -1.127506 2.00025)
			(end -0.853694 2.00025)
			(stroke
				(width 0.0127)
				(type default)
			)
			(layer "F.SilkS")
		)
		(fp_line
			(start -1.137158 2.009902)
			(end -0.844296 2.009902)
			(stroke
				(width 0.0127)
				(type default)
			)
			(layer "F.SilkS")
		)
		(fp_line
			(start -1.146556 2.0193)
			(end -0.834644 2.0193)
			(stroke
				(width 0.0127)
				(type default)
			)
			(layer "F.SilkS")
		)
		(fp_line
			(start -1.156208 2.028952)
			(end -0.825246 2.028952)
			(stroke
				(width 0.0127)
				(type default)
			)
			(layer "F.SilkS")
		)
		(fp_line
			(start -1.165606 2.03835)
			(end -0.815594 2.03835)
			(stroke
				(width 0.0127)
				(type default)
			)
			(layer "F.SilkS")
		)
		(fp_line
			(start -1.175258 2.048002)
			(end -0.806196 2.048002)
			(stroke
				(width 0.0127)
				(type default)
			)
			(layer "F.SilkS")
		)
		(fp_line
			(start -1.184656 2.0574)
			(end -0.796544 2.0574)
			(stroke
				(width 0.0127)
				(type default)
			)
			(layer "F.SilkS")
		)
		(fp_line
			(start -1.194308 2.067052)
			(end -0.787146 2.067052)
			(stroke
				(width 0.0127)
				(type default)
			)
			(layer "F.SilkS")
		)
		(fp_line
			(start -1.203706 2.07645)
			(end -0.777494 2.07645)
			(stroke
				(width 0.0127)
				(type default)
			)
			(layer "F.SilkS")
		)
		(fp_line
			(start -1.213358 2.086102)
			(end -0.768096 2.086102)
			(stroke
				(width 0.0127)
				(type default)
			)
			(layer "F.SilkS")
		)
		(fp_line
			(start -1.222756 2.0955)
			(end -0.758444 2.0955)
			(stroke
				(width 0.0127)
				(type default)
			)
			(layer "F.SilkS")
		)
		(fp_line
			(start -1.232408 2.105152)
			(end -0.749046 2.105152)
			(stroke
				(width 0.0127)
				(type default)
			)
			(layer "F.SilkS")
		)
		(fp_line
			(start -1.241806 2.11455)
			(end -0.739394 2.11455)
			(stroke
				(width 0.0127)
				(type default)
			)
			(layer "F.SilkS")
		)
		(fp_line
			(start -1.251458 2.124202)
			(end -0.729996 2.124202)
			(stroke
				(width 0.0127)
				(type default)
			)
			(layer "F.SilkS")
		)
		(fp_line
			(start -1.260856 2.1336)
			(end -0.720344 2.1336)
			(stroke
				(width 0.0127)
				(type default)
			)
			(layer "F.SilkS")
		)
		(fp_line
			(start -0.719074 2.145538)
			(end -1.265936 2.14122)
			(stroke
				(width 0.0127)
				(type default)
			)
			(layer "F.SilkS")
		)
		(fp_line
			(start -1.279398 2.152142)
			(end -0.9906 1.86309)
			(stroke
				(width 0.0127)
				(type default)
			)
			(layer "F.SilkS")
		)
		(fp_line
			(start -0.71628 2.15265)
			(end -1.26492 2.15265)
			(stroke
				(width 0.0127)
				(type default)
			)
			(layer "F.SilkS")
		)
		(fp_line
			(start -1.279144 2.15265)
			(end -0.701294 2.15265)
			(stroke
				(width 0.0127)
				(type default)
			)
			(layer "F.SilkS")
		)
		(fp_poly
			(pts
				(xy -1.285748 2.159) (xy -1.285748 1.8796) (xy -1.778 1.8796) (xy -1.778 -1.8796) (xy 1.778 -1.8796)
				(xy 1.778 1.8796) (xy -0.694944 1.8796) (xy -0.694944 2.159)
			)
			(stroke
				(width 0)
				(type default)
			)
			(fill no)
			(layer "F.CrtYd")
		)
		(fp_poly
			(pts
				(xy -1.285748 2.159) (xy -1.285748 1.8796) (xy -1.778 1.8796) (xy -1.778 -1.8796) (xy 1.778 -1.8796)
				(xy 1.778 1.8796) (xy -0.694944 1.8796) (xy -0.694944 2.159)
			)
			(stroke
				(width 0)
				(type default)
			)
			(fill no)
			(layer "F.Fab")
		)
		(pad "1" smd rect
			(at -0.98425 0.9525 90)
			(size 0.762 1.143)
			(layers "F.Cu" "F.Mask" "F.Paste")
			(net "NCT7904_D2+")
		)
		(pad "2" smd rect
			(at 0.98425 0.9525 90)
			(size 0.762 1.143)
			(layers "F.Cu" "F.Mask" "F.Paste")
			(net "NCT7904_D2-")
		)
		(pad "3" smd rect
			(at 0 -0.9525 90)
			(size 0.762 1.143)
			(layers "F.Cu" "F.Mask" "F.Paste")
			(net "NCT7904_D2+")
		)
	)
	(footprint ""
		(layer "F.Cu")
		(at 20.701 -185.5216)
		(property "Reference" "R85"
			(at 0 0 0)
			(layer "F.SilkS")
			(hide yes)
			(effects
				(font
					(size 1.27 1.27)
				)
			)
		)
		(property "Value" "27KR3F-GP"
			(at -0.0254 -2.5146 0)
			(unlocked yes)
			(layer "F.Fab")
			(hide yes)
			(effects
				(font
					(size 1.016 1.016)
					(thickness 0.1524)
				)
			)
		)
		(property "Device Type" "R603H22"
			(at -0.0254 -4.0386 0)
			(unlocked yes)
			(layer "F.Fab")
			(hide yes)
			(effects
				(font
					(size 1.016 1.016)
					(thickness 0.1524)
				)
			)
		)
		(duplicate_pad_numbers_are_jumpers no)
		(fp_line
			(start -0.4826 0)
			(end -0.2032 0)
			(stroke
				(width 0.2032)
				(type default)
			)
			(layer "F.SilkS")
		)
		(fp_line
			(start 0.2032 0)
			(end 0.4826 0)
			(stroke
				(width 0.2032)
				(type default)
			)
			(layer "F.SilkS")
		)
		(fp_rect
			(start -0.5842 1.3335)
			(end 0.5842 -1.3335)
			(stroke
				(width 0)
				(type default)
			)
			(fill no)
			(layer "F.CrtYd")
		)
		(fp_rect
			(start -0.5842 1.3335)
			(end 0.5842 -1.3335)
			(stroke
				(width 0)
				(type default)
			)
			(fill no)
			(layer "F.Fab")
		)
		(pad "1" smd custom
			(at 0 -0.762)
			(size 0.2159 0.2159)
			(layers "F.Cu" "F.Mask" "F.Paste")
			(net "FAN_TACH8")
			(options
				(clearance outline)
				(anchor circle)
			)
			(primitives
				(gr_poly
					(pts
						(arc
							(start -0.3302 -0.4318)
							(mid -0.402042 -0.402042)
							(end -0.4318 -0.3302)
						)
						(arc
							(start -0.4318 0.3302)
							(mid -0.402042 0.402042)
							(end -0.3302 0.4318)
						)
						(arc
							(start 0.3302 0.4318)
							(mid 0.402042 0.402042)
							(end 0.4318 0.3302)
						)
						(arc
							(start 0.4318 -0.3302)
							(mid 0.402042 -0.402042)
							(end 0.3302 -0.4318)
						)
					)
					(width 0)
					(fill yes)
				)
			)
		)
		(pad "2" smd custom
			(at 0 0.762)
			(size 0.2159 0.2159)
			(layers "F.Cu" "F.Mask" "F.Paste")
			(net "FANIN_8")
			(options
				(clearance outline)
				(anchor circle)
			)
			(primitives
				(gr_poly
					(pts
						(arc
							(start -0.3302 -0.4318)
							(mid -0.402042 -0.402042)
							(end -0.4318 -0.3302)
						)
						(arc
							(start -0.4318 0.3302)
							(mid -0.402042 0.402042)
							(end -0.3302 0.4318)
						)
						(arc
							(start 0.3302 0.4318)
							(mid 0.402042 0.402042)
							(end 0.4318 0.3302)
						)
						(arc
							(start 0.4318 -0.3302)
							(mid 0.402042 -0.402042)
							(end 0.3302 -0.4318)
						)
					)
					(width 0)
					(fill yes)
				)
			)
		)
	)
	(footprint ""
		(layer "F.Cu")
		(at 29.3624 -167.259 180)
		(property "Reference" "R162"
			(at 0 0 180)
			(layer "F.SilkS")
			(hide yes)
			(effects
				(font
					(size 1.27 1.27)
				)
			)
		)
		(property "Value" "0R2J-2-GP"
			(at 0.064008 -3.993896 180)
			(unlocked yes)
			(layer "F.Fab")
			(hide yes)
			(effects
				(font
					(size 1.016 1.016)
					(thickness 0.1524)
				)
			)
		)
		(property "Device Type" "R402H16"
			(at 0.064008 -5.517896 180)
			(unlocked yes)
			(layer "F.Fab")
			(hide yes)
			(effects
				(font
					(size 1.016 1.016)
					(thickness 0.1524)
				)
			)
		)
		(duplicate_pad_numbers_are_jumpers no)
		(fp_line
			(start 0.508 -0.9398)
			(end -0.508 -0.9398)
			(stroke
				(width 0.1524)
				(type default)
			)
			(layer "F.SilkS")
		)
		(fp_line
			(start -0.508 -0.9398)
			(end -0.508 0.9398)
			(stroke
				(width 0.1524)
				(type default)
			)
			(layer "F.SilkS")
		)
		(fp_rect
			(start -0.508 0.9398)
			(end 0.508 -0.9398)
			(stroke
				(width 0)
				(type default)
			)
			(fill no)
			(layer "F.CrtYd")
		)
		(fp_rect
			(start -0.508 0.9398)
			(end 0.508 -0.9398)
			(stroke
				(width 0)
				(type default)
			)
			(fill no)
			(layer "F.Fab")
		)
		(pad "1" smd custom
			(at 0 -0.4445 180)
			(size 0.1397 0.1397)
			(layers "F.Cu" "F.Mask" "F.Paste")
			(net "NCT7904D_PWM2")
			(options
				(clearance outline)
				(anchor circle)
			)
			(primitives
				(gr_poly
					(pts
						(arc
							(start -0.1778 -0.2794)
							(mid -0.249642 -0.249642)
							(end -0.2794 -0.1778)
						)
						(arc
							(start -0.2794 0.1778)
							(mid -0.249642 0.249642)
							(end -0.1778 0.2794)
						)
						(arc
							(start 0.1778 0.2794)
							(mid 0.249642 0.249642)
							(end 0.2794 0.1778)
						)
						(arc
							(start 0.2794 -0.1778)
							(mid 0.249642 -0.249642)
							(end 0.1778 -0.2794)
						)
					)
					(width 0)
					(fill yes)
				)
			)
		)
		(pad "2" smd custom
			(at 0 0.4445 180)
			(size 0.1397 0.1397)
			(layers "F.Cu" "F.Mask" "F.Paste")
			(net "PWM_BUFFER_IN_FAN3_FAN4")
			(options
				(clearance outline)
				(anchor circle)
			)
			(primitives
				(gr_poly
					(pts
						(arc
							(start -0.1778 -0.2794)
							(mid -0.249642 -0.249642)
							(end -0.2794 -0.1778)
						)
						(arc
							(start -0.2794 0.1778)
							(mid -0.249642 0.249642)
							(end -0.1778 0.2794)
						)
						(arc
							(start 0.1778 0.2794)
							(mid 0.249642 0.249642)
							(end 0.2794 0.1778)
						)
						(arc
							(start 0.2794 -0.1778)
							(mid 0.249642 -0.249642)
							(end 0.1778 -0.2794)
						)
					)
					(width 0)
					(fill yes)
				)
			)
		)
	)
	(footprint ""
		(layer "F.Cu")
		(at 22.225 -18.161 90)
		(property "Reference" "R75"
			(at 0 0 90)
			(layer "F.SilkS")
			(hide yes)
			(effects
				(font
					(size 1.27 1.27)
				)
			)
		)
		(property "Value" "10KR2F-2-GP"
			(at 0.064008 -3.993896 90)
			(unlocked yes)
			(layer "F.Fab")
			(hide yes)
			(effects
				(font
					(size 1.016 1.016)
					(thickness 0.1524)
				)
			)
		)
		(property "Device Type" "R402H16"
			(at 0.064008 -5.517896 90)
			(unlocked yes)
			(layer "F.Fab")
			(hide yes)
			(effects
				(font
					(size 1.016 1.016)
					(thickness 0.1524)
				)
			)
		)
		(duplicate_pad_numbers_are_jumpers no)
		(fp_line
			(start 0.508 -0.9398)
			(end -0.508 -0.9398)
			(stroke
				(width 0.1524)
				(type default)
			)
			(layer "F.SilkS")
		)
		(fp_line
			(start -0.508 -0.9398)
			(end -0.508 0.9398)
			(stroke
				(width 0.1524)
				(type default)
			)
			(layer "F.SilkS")
		)
		(fp_rect
			(start -0.508 0.9398)
			(end 0.508 -0.9398)
			(stroke
				(width 0)
				(type default)
			)
			(fill no)
			(layer "F.CrtYd")
		)
		(fp_rect
			(start -0.508 0.9398)
			(end 0.508 -0.9398)
			(stroke
				(width 0)
				(type default)
			)
			(fill no)
			(layer "F.Fab")
		)
		(pad "1" smd custom
			(at 0 -0.4445 90)
			(size 0.1397 0.1397)
			(layers "F.Cu" "F.Mask" "F.Paste")
			(net "FANIN_12")
			(options
				(clearance outline)
				(anchor circle)
			)
			(primitives
				(gr_poly
					(pts
						(arc
							(start -0.1778 -0.2794)
							(mid -0.249642 -0.249642)
							(end -0.2794 -0.1778)
						)
						(arc
							(start -0.2794 0.1778)
							(mid -0.249642 0.249642)
							(end -0.1778 0.2794)
						)
						(arc
							(start 0.1778 0.2794)
							(mid 0.249642 0.249642)
							(end 0.2794 0.1778)
						)
						(arc
							(start 0.2794 -0.1778)
							(mid 0.249642 -0.249642)
							(end 0.1778 -0.2794)
						)
					)
					(width 0)
					(fill yes)
				)
			)
		)
		(pad "2" smd custom
			(at 0 0.4445 90)
			(size 0.1397 0.1397)
			(layers "F.Cu" "F.Mask" "F.Paste")
			(net "GND")
			(options
				(clearance outline)
				(anchor circle)
			)
			(primitives
				(gr_poly
					(pts
						(arc
							(start -0.1778 -0.2794)
							(mid -0.249642 -0.249642)
							(end -0.2794 -0.1778)
						)
						(arc
							(start -0.2794 0.1778)
							(mid -0.249642 0.249642)
							(end -0.1778 0.2794)
						)
						(arc
							(start 0.1778 0.2794)
							(mid 0.249642 0.249642)
							(end 0.2794 0.1778)
						)
						(arc
							(start 0.2794 -0.1778)
							(mid 0.249642 -0.249642)
							(end 0.1778 -0.2794)
						)
					)
					(width 0)
					(fill yes)
				)
			)
		)
	)
)
